# T6G (Grand Teton) — schematic netlist excerpt (pin names and nets, part order shuffled) for the footprints in the layout excerpt that follows; sources: Cadence DE-HDL packaged netlist, KiCad conversion of 04192023_DAF0TMB3IC0_F0TG_MB_C_brd_V02_OCP.brd

R4195  Q_RES  1K 1% CHIP  pkg 0402LF  page 235 : A = U272_2_ADD1 ; B = GND
R6144  Q_RES  1K 1% CHIP  pkg 0402LF  page 84 : A = FM_BOARD_BMC_SKU_ID1 ; B = GND
R609  Q_RES  0 5% CHIP  pkg 0201LF  page 320 : A = CLK_100M_RETIMER_CPU1_P0_R_DN ; B = CLK_100M_RETIMER_CPU1_P0_DN

(kicad_pcb
	(version 20260206)
	(generator "pcbnew")
	(generator_version "10.0")
	(general
		(thickness 1.6)
		(legacy_teardrops no)
	)
	(paper "A4")
	(title_block
		(title "04192023_DAF0TMB3IC0_F0TG_MB_C_brd_V02_OCP.brd")
		(comment 1 "Grand Teton / footprints 1958-1960 of 8354")
	)
	(layers
		(0 "F.Cu" signal "TOP")
		(4 "In1.Cu" signal "GND")
		(6 "In2.Cu" signal "IN1")
		(8 "In3.Cu" signal "GND1")
		(10 "In4.Cu" signal "IN2")
		(12 "In5.Cu" signal "GND2")
		(14 "In6.Cu" signal "IN3")
		(16 "In7.Cu" signal "GND3")
		(18 "In8.Cu" signal "VCC")
		(20 "In9.Cu" signal "VCC1")
		(22 "In10.Cu" signal "GND4")
		(24 "In11.Cu" signal "IN4")
		(26 "In12.Cu" signal "GND5")
		(28 "In13.Cu" signal "IN5")
		(30 "In14.Cu" signal "GND6")
		(32 "In15.Cu" signal "IN6")
		(34 "In16.Cu" signal "GND7")
		(2 "B.Cu" signal "BOTTOM")
		(9 "F.Adhes" user "F.Adhesive")
		(11 "B.Adhes" user "B.Adhesive")
		(13 "F.Paste" user "Package Geometry/Pastemask Top")
		(15 "B.Paste" user "Package Geometry/Pastemask Bottom")
		(5 "F.SilkS" user "Ref Des/Silkscreen Top")
		(7 "B.SilkS" user "Ref Des/Silkscreen Bottom")
		(1 "F.Mask" user "Board Geometry/Soldermask Top")
		(3 "B.Mask" user "Board Geometry/Soldermask Bottom")
		(17 "Dwgs.User" user "User.Drawings")
		(19 "Cmts.User" user "User.Comments")
		(21 "Eco1.User" user "User.Eco1")
		(23 "Eco2.User" user "User.Eco2")
		(25 "Edge.Cuts" user "Board Geometry/Outline")
		(27 "Margin" user)
		(31 "F.CrtYd" user "Package Geometry/Place Bound Top")
		(29 "B.CrtYd" user "Package Geometry/Place Bound Bottom")
		(35 "F.Fab" user "Ref Des/Assembly Top")
		(33 "B.Fab" user "Ref Des/Assembly Bottom")
	)
	(footprint ""
		(layer "F.Cu")
		(at 42.527982 -386.951474)
		(property "Reference" "R609"
			(at 0 0 0)
			(layer "F.SilkS")
			(hide yes)
			(effects
				(font
					(size 1.27 1.27)
				)
			)
		)
		(property "Value" ""
			(at 0 0 0)
			(layer "F.Fab")
			(effects
				(font
					(size 1.27 1.27)
				)
			)
		)
		(duplicate_pad_numbers_are_jumpers no)
		(fp_line
			(start -0.32512 -0.175006)
			(end 0.32512 -0.175006)
			(stroke
				(width 0.1)
				(type default)
			)
			(layer "F.Fab")
		)
		(fp_line
			(start -0.32512 0.175006)
			(end -0.32512 -0.175006)
			(stroke
				(width 0.1)
				(type default)
			)
			(layer "F.Fab")
		)
		(fp_line
			(start 0.32512 -0.175006)
			(end 0.32512 0.175006)
			(stroke
				(width 0.1)
				(type default)
			)
			(layer "F.Fab")
		)
		(fp_line
			(start 0.32512 0.175006)
			(end -0.32512 0.175006)
			(stroke
				(width 0.1)
				(type default)
			)
			(layer "F.Fab")
		)
		(pad "1" smd rect
			(at -0.2667 0)
			(size 0.3048 0.381)
			(layers "F.Cu" "F.Mask" "F.Paste")
			(net "CLK_100M_RETIMER_CPU1_P0_R_DN")
		)
		(pad "2" smd rect
			(at 0.2667 0 180)
			(size 0.3048 0.381)
			(layers "F.Cu" "F.Mask" "F.Paste")
			(net "CLK_100M_RETIMER_CPU1_P0_DN")
		)
	)
	(footprint ""
		(layer "F.Cu")
		(at 171.269406 -125.751336 180)
		(property "Reference" "R6144"
			(at 0 0 180)
			(layer "F.SilkS")
			(hide yes)
			(effects
				(font
					(size 1.27 1.27)
				)
			)
		)
		(property "Value" ""
			(at 0 0 180)
			(layer "F.Fab")
			(effects
				(font
					(size 1.27 1.27)
				)
			)
		)
		(duplicate_pad_numbers_are_jumpers no)
		(fp_line
			(start 0.7874 0.4064)
			(end -0.7874 0.4064)
			(stroke
				(width 0.1524)
				(type default)
			)
			(layer "F.SilkS")
		)
		(fp_line
			(start 0.7874 -0.4064)
			(end 0.7874 0.4064)
			(stroke
				(width 0.1524)
				(type default)
			)
			(layer "F.SilkS")
		)
		(fp_line
			(start -0.7874 0.4064)
			(end -0.7874 -0.4064)
			(stroke
				(width 0.1524)
				(type default)
			)
			(layer "F.SilkS")
		)
		(fp_line
			(start -0.7874 -0.4064)
			(end 0.7874 -0.4064)
			(stroke
				(width 0.1524)
				(type default)
			)
			(layer "F.SilkS")
		)
		(fp_line
			(start 0.67945 0.3048)
			(end 0.120396 0.3048)
			(stroke
				(width 0.1)
				(type default)
			)
			(layer "F.Fab")
		)
		(fp_line
			(start 0.67945 -0.3048)
			(end 0.67945 0.3048)
			(stroke
				(width 0.1)
				(type default)
			)
			(layer "F.Fab")
		)
		(fp_line
			(start 0.12065 -0.2794)
			(end 0.12065 -0.3048)
			(stroke
				(width 0.1)
				(type default)
			)
			(layer "F.Fab")
		)
		(fp_line
			(start 0.12065 -0.3048)
			(end 0.67945 -0.3048)
			(stroke
				(width 0.1)
				(type default)
			)
			(layer "F.Fab")
		)
		(fp_line
			(start 0.120396 0.3048)
			(end 0.120396 0.2794)
			(stroke
				(width 0.1)
				(type default)
			)
			(layer "F.Fab")
		)
		(fp_line
			(start 0.120396 0.2794)
			(end -0.12065 0.2794)
			(stroke
				(width 0.1)
				(type default)
			)
			(layer "F.Fab")
		)
		(fp_line
			(start -0.12065 0.3048)
			(end -0.67945 0.3048)
			(stroke
				(width 0.1)
				(type default)
			)
			(layer "F.Fab")
		)
		(fp_line
			(start -0.12065 0.2794)
			(end -0.12065 0.3048)
			(stroke
				(width 0.1)
				(type default)
			)
			(layer "F.Fab")
		)
		(fp_line
			(start -0.12065 -0.2794)
			(end 0.12065 -0.2794)
			(stroke
				(width 0.1)
				(type default)
			)
			(layer "F.Fab")
		)
		(fp_line
			(start -0.12065 -0.305054)
			(end -0.12065 -0.2794)
			(stroke
				(width 0.1)
				(type default)
			)
			(layer "F.Fab")
		)
		(fp_line
			(start -0.67945 0.3048)
			(end -0.67945 -0.305054)
			(stroke
				(width 0.1)
				(type default)
			)
			(layer "F.Fab")
		)
		(fp_line
			(start -0.67945 -0.305054)
			(end -0.12065 -0.305054)
			(stroke
				(width 0.1)
				(type default)
			)
			(layer "F.Fab")
		)
		(pad "1" smd circle
			(at -0.40005 0 180)
			(size 0 0)
			(layers "F.Cu" "F.Mask" "F.Paste")
			(net "FM_BOARD_BMC_SKU_ID1")
		)
		(pad "2" smd circle
			(at 0.40005 0 180)
			(size 0 0)
			(layers "F.Cu" "F.Mask" "F.Paste")
			(net "GND")
		)
	)
	(footprint ""
		(layer "F.Cu")
		(at 100.285296 -422.43248 90)
		(property "Reference" "R4195"
			(at 0 0 90)
			(layer "F.SilkS")
			(hide yes)
			(effects
				(font
					(size 1.27 1.27)
				)
			)
		)
		(property "Value" ""
			(at 0 0 90)
			(layer "F.Fab")
			(effects
				(font
					(size 1.27 1.27)
				)
			)
		)
		(duplicate_pad_numbers_are_jumpers no)
		(fp_line
			(start 0.7874 -0.4064)
			(end 0.7874 0.4064)
			(stroke
				(width 0.1524)
				(type default)
			)
			(layer "F.SilkS")
		)
		(fp_line
			(start -0.7874 -0.4064)
			(end 0.7874 -0.4064)
			(stroke
				(width 0.1524)
				(type default)
			)
			(layer "F.SilkS")
		)
		(fp_line
			(start 0.7874 0.4064)
			(end -0.7874 0.4064)
			(stroke
				(width 0.1524)
				(type default)
			)
			(layer "F.SilkS")
		)
		(fp_line
			(start -0.7874 0.4064)
			(end -0.7874 -0.4064)
			(stroke
				(width 0.1524)
				(type default)
			)
			(layer "F.SilkS")
		)
		(fp_line
			(start -0.12065 -0.305054)
			(end -0.12065 -0.2794)
			(stroke
				(width 0.1)
				(type default)
			)
			(layer "F.Fab")
		)
		(fp_line
			(start -0.67945 -0.305054)
			(end -0.12065 -0.305054)
			(stroke
				(width 0.1)
				(type default)
			)
			(layer "F.Fab")
		)
		(fp_line
			(start 0.67945 -0.3048)
			(end 0.67945 0.3048)
			(stroke
				(width 0.1)
				(type default)
			)
			(layer "F.Fab")
		)
		(fp_line
			(start 0.12065 -0.3048)
			(end 0.67945 -0.3048)
			(stroke
				(width 0.1)
				(type default)
			)
			(layer "F.Fab")
		)
		(fp_line
			(start 0.12065 -0.2794)
			(end 0.12065 -0.3048)
			(stroke
				(width 0.1)
				(type default)
			)
			(layer "F.Fab")
		)
		(fp_line
			(start -0.12065 -0.2794)
			(end 0.12065 -0.2794)
			(stroke
				(width 0.1)
				(type default)
			)
			(layer "F.Fab")
		)
		(fp_line
			(start 0.120396 0.2794)
			(end -0.12065 0.2794)
			(stroke
				(width 0.1)
				(type default)
			)
			(layer "F.Fab")
		)
		(fp_line
			(start -0.12065 0.2794)
			(end -0.12065 0.3048)
			(stroke
				(width 0.1)
				(type default)
			)
			(layer "F.Fab")
		)
		(fp_line
			(start 0.67945 0.3048)
			(end 0.120396 0.3048)
			(stroke
				(width 0.1)
				(type default)
			)
			(layer "F.Fab")
		)
		(fp_line
			(start 0.120396 0.3048)
			(end 0.120396 0.2794)
			(stroke
				(width 0.1)
				(type default)
			)
			(layer "F.Fab")
		)
		(fp_line
			(start -0.12065 0.3048)
			(end -0.67945 0.3048)
			(stroke
				(width 0.1)
				(type default)
			)
			(layer "F.Fab")
		)
		(fp_line
			(start -0.67945 0.3048)
			(end -0.67945 -0.305054)
			(stroke
				(width 0.1)
				(type default)
			)
			(layer "F.Fab")
		)
		(pad "1" smd circle
			(at -0.40005 0 90)
			(size 0 0)
			(layers "F.Cu" "F.Mask" "F.Paste")
			(net "U272_2_ADD1")
		)
		(pad "2" smd circle
			(at 0.40005 0 90)
			(size 0 0)
			(layers "F.Cu" "F.Mask" "F.Paste")
			(net "GND")
		)
	)
)
